(kicad_pcb
	(version 20260206)
	(generator "pcbnew")
	(generator_version "10.0")
	(general
		(thickness 1.6)
		(legacy_teardrops no)
	)
	(paper "A4")
	(title_block
		(title "Wiwynn_Tioga_Pass_MB.brd")
		(comment 1 "Tioga Pass / footprints 2175-2177 of 4770")
	)
	(layers
		(0 "F.Cu" signal "TOP")
		(4 "In1.Cu" signal "L2GND")
		(6 "In2.Cu" signal "L3")
		(8 "In3.Cu" signal "L4GND")
		(10 "In4.Cu" signal "L5")
		(12 "In5.Cu" signal "L6GND")
		(14 "In6.Cu" signal "L7VCC")
		(16 "In7.Cu" signal "L8VCC")
		(18 "In8.Cu" signal "L9GND")
		(20 "In9.Cu" signal "L10")
		(22 "In10.Cu" signal "L11GND")
		(24 "In11.Cu" signal "L12")
		(26 "In12.Cu" signal "L13GND")
		(2 "B.Cu" signal "BOTTOM")
		(9 "F.Adhes" user "F.Adhesive")
		(11 "B.Adhes" user "B.Adhesive")
		(13 "F.Paste" user "Package Geometry/Pastemask Top")
		(15 "B.Paste" user "Package Geometry/Pastemask Bottom")
		(5 "F.SilkS" user "Ref Des/Silkscreen Top")
		(7 "B.SilkS" user "Ref Des/Silkscreen Bottom")
		(1 "F.Mask" user "Board Geometry/Soldermask Top")
		(3 "B.Mask" user "Board Geometry/Soldermask Bottom")
		(17 "Dwgs.User" user "User.Drawings")
		(19 "Cmts.User" user "User.Comments")
		(21 "Eco1.User" user "User.Eco1")
		(23 "Eco2.User" user "User.Eco2")
		(25 "Edge.Cuts" user "Board Geometry/Outline")
		(27 "Margin" user)
		(31 "F.CrtYd" user "Package Geometry/Place Bound Top")
		(29 "B.CrtYd" user "Package Geometry/Place Bound Bottom")
		(35 "F.Fab" user "Ref Des/Assembly Top")
		(33 "B.Fab" user "Ref Des/Assembly Bottom")
	)
	(footprint ""
		(layer "F.Cu")
		(at 13.8938 -24.13 90)
		(property "Reference" "C1F18"
			(at 0 0 90)
			(layer "F.SilkS")
			(hide yes)
			(effects
				(font
					(size 1.27 1.27)
				)
			)
		)
		(property "Value" ""
			(at 0 0 90)
			(layer "F.Fab")
			(effects
				(font
					(size 1.27 1.27)
				)
			)
		)
		(duplicate_pad_numbers_are_jumpers no)
		(fp_rect
			(start -0.3048 -0.1016)
			(end 0.3048 0.9906)
			(stroke
				(width 0)
				(type default)
			)
			(fill no)
			(layer "F.CrtYd")
		)
		(fp_line
			(start 0.3048 -0.1016)
			(end -0.3048 -0.1016)
			(stroke
				(width 0.1)
				(type default)
			)
			(layer "F.Fab")
		)
		(fp_line
			(start -0.3048 -0.1016)
			(end -0.3048 0.9906)
			(stroke
				(width 0.1)
				(type default)
			)
			(layer "F.Fab")
		)
		(fp_line
			(start 0.3048 0.9906)
			(end 0.3048 -0.1016)
			(stroke
				(width 0.1)
				(type default)
			)
			(layer "F.Fab")
		)
		(fp_line
			(start -0.3048 0.9906)
			(end 0.3048 0.9906)
			(stroke
				(width 0.1)
				(type default)
			)
			(layer "F.Fab")
		)
		(pad "1" smd rect
			(at 0 0 90)
			(size 0.508 0.508)
			(layers "F.Cu" "F.Mask" "F.Paste")
			(net "P3E_CPU1_PE3_MP_C_TXP<0>")
		)
		(pad "2" smd rect
			(at 0 0.889 90)
			(size 0.508 0.508)
			(layers "F.Cu" "F.Mask" "F.Paste")
			(net "P3E_CPU1_PE3_MP_TXP<0>")
		)
		(zone
			(layer "F.Cu")
			(hatch none 0.5)
			(connect_pads
				(clearance 0)
			)
			(min_thickness 0.25)
			(keepout
				(tracks allowed)
				(vias not_allowed)
				(pads allowed)
				(copperpour not_allowed)
				(footprints allowed)
			)
			(placement
				(enabled no)
				(sheetname "")
			)
			(fill
				(thermal_gap 0.5)
				(thermal_bridge_width 0.5)
				(island_removal_mode 0)
			)
			(polygon
				(pts
					(xy 14.1478 -23.876) (xy 14.5288 -23.876) (xy 14.5288 -24.384) (xy 14.1478 -24.384)
				)
			)
		)
		(zone
			(layer "F.Cu")
			(hatch none 0.5)
			(connect_pads
				(clearance 0)
			)
			(min_thickness 0.25)
			(keepout
				(tracks not_allowed)
				(vias allowed)
				(pads allowed)
				(copperpour not_allowed)
				(footprints allowed)
			)
			(placement
				(enabled no)
				(sheetname "")
			)
			(fill
				(thermal_gap 0.5)
				(thermal_bridge_width 0.5)
				(island_removal_mode 0)
			)
			(polygon
				(pts
					(xy 14.1478 -23.876) (xy 14.5288 -23.876) (xy 14.5288 -24.384) (xy 14.1478 -24.384)
				)
			)
		)
	)
	(footprint ""
		(layer "F.Cu")
		(at 378.926344 -10.941558)
		(property "Reference" "C7G20"
			(at 0 0 0)
			(layer "F.SilkS")
			(hide yes)
			(effects
				(font
					(size 1.27 1.27)
				)
			)
		)
		(property "Value" ""
			(at 0 0 0)
			(layer "F.Fab")
			(effects
				(font
					(size 1.27 1.27)
				)
			)
		)
		(duplicate_pad_numbers_are_jumpers no)
		(fp_rect
			(start -0.3048 0.9906)
			(end 0.3048 -0.1016)
			(stroke
				(width 0)
				(type default)
			)
			(fill no)
			(layer "F.CrtYd")
		)
		(fp_line
			(start -0.3048 -0.1016)
			(end -0.3048 0.9906)
			(stroke
				(width 0.1)
				(type default)
			)
			(layer "F.Fab")
		)
		(fp_line
			(start -0.3048 0.9906)
			(end 0.3048 0.9906)
			(stroke
				(width 0.1)
				(type default)
			)
			(layer "F.Fab")
		)
		(fp_line
			(start 0.3048 -0.1016)
			(end -0.3048 -0.1016)
			(stroke
				(width 0.1)
				(type default)
			)
			(layer "F.Fab")
		)
		(fp_line
			(start 0.3048 0.9906)
			(end 0.3048 -0.1016)
			(stroke
				(width 0.1)
				(type default)
			)
			(layer "F.Fab")
		)
		(pad "1" smd rect
			(at 0 0)
			(size 0.508 0.508)
			(layers "F.Cu" "F.Mask" "F.Paste")
			(net "P3E_CPU0_PE2_SS_TXP<8>")
		)
		(pad "2" smd rect
			(at 0 0.889)
			(size 0.508 0.508)
			(layers "F.Cu" "F.Mask" "F.Paste")
			(net "P3E_CPU0_PE2_SS_C_TXP<8>")
		)
		(zone
			(layer "F.Cu")
			(hatch none 0.5)
			(connect_pads
				(clearance 0)
			)
			(min_thickness 0.25)
			(keepout
				(tracks allowed)
				(vias not_allowed)
				(pads allowed)
				(copperpour not_allowed)
				(footprints allowed)
			)
			(placement
				(enabled no)
				(sheetname "")
			)
			(fill
				(thermal_gap 0.5)
				(thermal_bridge_width 0.5)
				(island_removal_mode 0)
			)
			(polygon
				(pts
					(xy 378.672344 -10.306558) (xy 379.180344 -10.306558) (xy 379.180344 -10.687558) (xy 378.672344 -10.687558)
				)
			)
		)
	)
	(footprint ""
		(layer "F.Cu")
		(at 452.247 -28.7655)
		(property "Reference" "C25W3"
			(at -0.8382 -0.67818 0)
			(unlocked yes)
			(layer "F.SilkS")
			(effects
				(font
					(size 0.4064 0.254)
					(thickness 0.1524)
				)
				(justify left)
			)
		)
		(property "Value" ""
			(at 0 0 0)
			(layer "F.Fab")
			(effects
				(font
					(size 1.27 1.27)
				)
			)
		)
		(duplicate_pad_numbers_are_jumpers no)
		(fp_poly
			(pts
				(xy 0.3048 -0.1016) (xy 0.3048 0.9906) (xy -0.3048 0.9906) (xy -0.3048 -0.1016)
			)
			(stroke
				(width 0)
				(type default)
			)
			(fill no)
			(layer "F.CrtYd")
		)
		(fp_line
			(start -0.3048 -0.1016)
			(end -0.3048 0.9906)
			(stroke
				(width 0.1)
				(type default)
			)
			(layer "F.Fab")
		)
		(fp_line
			(start -0.3048 0.9906)
			(end 0.3048 0.9906)
			(stroke
				(width 0.1)
				(type default)
			)
			(layer "F.Fab")
		)
		(fp_line
			(start 0.3048 -0.1016)
			(end -0.3048 -0.1016)
			(stroke
				(width 0.1)
				(type default)
			)
			(layer "F.Fab")
		)
		(fp_line
			(start 0.3048 0.9906)
			(end 0.3048 -0.1016)
			(stroke
				(width 0.1)
				(type default)
			)
			(layer "F.Fab")
		)
		(pad "1" smd rect
			(at 0 0)
			(size 0.508 0.508)
			(layers "F.Cu" "F.Mask" "F.Paste")
			(net "P1V2_AUX_BMC")
		)
		(pad "2" smd rect
			(at 0 0.889)
			(size 0.508 0.508)
			(layers "F.Cu" "F.Mask" "F.Paste")
			(net "GND")
		)
		(zone
			(layer "F.Cu")
			(hatch none 0.5)
			(connect_pads
				(clearance 0)
			)
			(min_thickness 0.25)
			(keepout
				(tracks allowed)
				(vias not_allowed)
				(pads allowed)
				(copperpour not_allowed)
				(footprints allowed)
			)
			(placement
				(enabled no)
				(sheetname "")
			)
			(fill
				(thermal_gap 0.5)
				(thermal_bridge_width 0.5)
				(island_removal_mode 0)
			)
			(polygon
				(pts
					(xy 451.993 -28.5115) (xy 452.501 -28.5115) (xy 452.501 -28.1305) (xy 451.993 -28.1305)
				)
			)
		)
		(zone
			(layer "F.Cu")
			(hatch none 0.5)
			(connect_pads
				(clearance 0)
			)
			(min_thickness 0.25)
			(keepout
				(tracks not_allowed)
				(vias allowed)
				(pads allowed)
				(copperpour not_allowed)
				(footprints allowed)
			)
			(placement
				(enabled no)
				(sheetname "")
			)
			(fill
				(thermal_gap 0.5)
				(thermal_bridge_width 0.5)
				(island_removal_mode 0)
			)
			(polygon
				(pts
					(xy 451.993 -28.1305) (xy 452.501 -28.1305) (xy 452.501 -28.5115) (xy 451.993 -28.5115)
				)
			)
		)
	)
)
